# T6G (Grand Teton) — schematic netlist excerpt (pin names and nets, part order shuffled) for the footprints in the layout excerpt that follows; sources: Cadence DE-HDL packaged netlist, KiCad conversion of 04192023_DAF0TMB3IC0_F0TG_MB_C_brd_V02_OCP.brd

PC560  Q_CAP  0.22UF 16V 10% X7R  pkg 0402  page 195 : A = SW_PVDDCR_CPU0_P0_BOOT3_RC ; B = SW_PVDDCR_CPU0_P0_PH3
PR833  Q_RES  1.5K 1% EMPTY  pkg 0402LF  page 190 : A = P3V3_AUX_SS ; B = GND

(kicad_pcb
	(version 20260206)
	(generator "pcbnew")
	(generator_version "10.0")
	(general
		(thickness 1.6)
		(legacy_teardrops no)
	)
	(paper "A4")
	(title_block
		(title "04192023_DAF0TMB3IC0_F0TG_MB_C_brd_V02_OCP.brd")
		(comment 1 "Grand Teton / footprints 4286-4287 of 8354")
	)
	(layers
		(0 "F.Cu" signal "TOP")
		(4 "In1.Cu" signal "GND")
		(6 "In2.Cu" signal "IN1")
		(8 "In3.Cu" signal "GND1")
		(10 "In4.Cu" signal "IN2")
		(12 "In5.Cu" signal "GND2")
		(14 "In6.Cu" signal "IN3")
		(16 "In7.Cu" signal "GND3")
		(18 "In8.Cu" signal "VCC")
		(20 "In9.Cu" signal "VCC1")
		(22 "In10.Cu" signal "GND4")
		(24 "In11.Cu" signal "IN4")
		(26 "In12.Cu" signal "GND5")
		(28 "In13.Cu" signal "IN5")
		(30 "In14.Cu" signal "GND6")
		(32 "In15.Cu" signal "IN6")
		(34 "In16.Cu" signal "GND7")
		(2 "B.Cu" signal "BOTTOM")
		(9 "F.Adhes" user "F.Adhesive")
		(11 "B.Adhes" user "B.Adhesive")
		(13 "F.Paste" user "Package Geometry/Pastemask Top")
		(15 "B.Paste" user "Package Geometry/Pastemask Bottom")
		(5 "F.SilkS" user "Ref Des/Silkscreen Top")
		(7 "B.SilkS" user "Ref Des/Silkscreen Bottom")
		(1 "F.Mask" user "Board Geometry/Soldermask Top")
		(3 "B.Mask" user "Board Geometry/Soldermask Bottom")
		(17 "Dwgs.User" user "User.Drawings")
		(19 "Cmts.User" user "User.Comments")
		(21 "Eco1.User" user "User.Eco1")
		(23 "Eco2.User" user "User.Eco2")
		(25 "Edge.Cuts" user "Board Geometry/Outline")
		(27 "Margin" user)
		(31 "F.CrtYd" user "Package Geometry/Place Bound Top")
		(29 "B.CrtYd" user "Package Geometry/Place Bound Bottom")
		(35 "F.Fab" user "Ref Des/Assembly Top")
		(33 "B.Fab" user "Ref Des/Assembly Bottom")
	)
	(footprint ""
		(layer "F.Cu")
		(at 379.292104 -178.0921 90)
		(property "Reference" "PC560"
			(at 0 0 90)
			(layer "F.SilkS")
			(hide yes)
			(effects
				(font
					(size 1.27 1.27)
				)
			)
		)
		(property "Value" ""
			(at 0 0 90)
			(layer "F.Fab")
			(effects
				(font
					(size 1.27 1.27)
				)
			)
		)
		(duplicate_pad_numbers_are_jumpers no)
		(fp_line
			(start 0.7874 -0.4064)
			(end 0.7874 0.4064)
			(stroke
				(width 0.1524)
				(type default)
			)
			(layer "F.SilkS")
		)
		(fp_line
			(start -0.7874 -0.4064)
			(end 0.7874 -0.4064)
			(stroke
				(width 0.1524)
				(type default)
			)
			(layer "F.SilkS")
		)
		(fp_line
			(start 0.7874 0.4064)
			(end -0.7874 0.4064)
			(stroke
				(width 0.1524)
				(type default)
			)
			(layer "F.SilkS")
		)
		(fp_line
			(start -0.7874 0.4064)
			(end -0.7874 -0.4064)
			(stroke
				(width 0.1524)
				(type default)
			)
			(layer "F.SilkS")
		)
		(fp_line
			(start -0.12065 -0.305054)
			(end -0.12065 -0.2794)
			(stroke
				(width 0.1)
				(type default)
			)
			(layer "F.Fab")
		)
		(fp_line
			(start -0.67945 -0.305054)
			(end -0.12065 -0.305054)
			(stroke
				(width 0.1)
				(type default)
			)
			(layer "F.Fab")
		)
		(fp_line
			(start 0.67945 -0.3048)
			(end 0.67945 0.3048)
			(stroke
				(width 0.1)
				(type default)
			)
			(layer "F.Fab")
		)
		(fp_line
			(start 0.12065 -0.3048)
			(end 0.67945 -0.3048)
			(stroke
				(width 0.1)
				(type default)
			)
			(layer "F.Fab")
		)
		(fp_line
			(start 0.12065 -0.2794)
			(end 0.12065 -0.3048)
			(stroke
				(width 0.1)
				(type default)
			)
			(layer "F.Fab")
		)
		(fp_line
			(start -0.12065 -0.2794)
			(end 0.12065 -0.2794)
			(stroke
				(width 0.1)
				(type default)
			)
			(layer "F.Fab")
		)
		(fp_line
			(start 0.120396 0.2794)
			(end -0.12065 0.2794)
			(stroke
				(width 0.1)
				(type default)
			)
			(layer "F.Fab")
		)
		(fp_line
			(start -0.12065 0.2794)
			(end -0.12065 0.3048)
			(stroke
				(width 0.1)
				(type default)
			)
			(layer "F.Fab")
		)
		(fp_line
			(start 0.67945 0.3048)
			(end 0.120396 0.3048)
			(stroke
				(width 0.1)
				(type default)
			)
			(layer "F.Fab")
		)
		(fp_line
			(start 0.120396 0.3048)
			(end 0.120396 0.2794)
			(stroke
				(width 0.1)
				(type default)
			)
			(layer "F.Fab")
		)
		(fp_line
			(start -0.12065 0.3048)
			(end -0.67945 0.3048)
			(stroke
				(width 0.1)
				(type default)
			)
			(layer "F.Fab")
		)
		(fp_line
			(start -0.67945 0.3048)
			(end -0.67945 -0.305054)
			(stroke
				(width 0.1)
				(type default)
			)
			(layer "F.Fab")
		)
		(pad "1" smd circle
			(at -0.40005 0 90)
			(size 0 0)
			(layers "F.Cu" "F.Mask" "F.Paste")
			(net "SW_PVDDCR_CPU0_P0_BOOT3_RC")
		)
		(pad "2" smd circle
			(at 0.40005 0 90)
			(size 0 0)
			(layers "F.Cu" "F.Mask" "F.Paste")
			(net "SW_PVDDCR_CPU0_P0_PH3")
		)
	)
	(footprint ""
		(layer "F.Cu")
		(at 454.611994 -46.264576 -90)
		(property "Reference" "PR833"
			(at 0 0 270)
			(layer "F.SilkS")
			(hide yes)
			(effects
				(font
					(size 1.27 1.27)
				)
			)
		)
		(property "Value" ""
			(at 0 0 270)
			(layer "F.Fab")
			(effects
				(font
					(size 1.27 1.27)
				)
			)
		)
		(duplicate_pad_numbers_are_jumpers no)
		(fp_line
			(start -0.7874 0.4064)
			(end -0.7874 -0.4064)
			(stroke
				(width 0.1524)
				(type default)
			)
			(layer "F.SilkS")
		)
		(fp_line
			(start 0.7874 0.4064)
			(end -0.7874 0.4064)
			(stroke
				(width 0.1524)
				(type default)
			)
			(layer "F.SilkS")
		)
		(fp_line
			(start -0.7874 -0.4064)
			(end 0.7874 -0.4064)
			(stroke
				(width 0.1524)
				(type default)
			)
			(layer "F.SilkS")
		)
		(fp_line
			(start 0.7874 -0.4064)
			(end 0.7874 0.4064)
			(stroke
				(width 0.1524)
				(type default)
			)
			(layer "F.SilkS")
		)
		(fp_line
			(start -0.67945 0.3048)
			(end -0.67945 -0.305054)
			(stroke
				(width 0.1)
				(type default)
			)
			(layer "F.Fab")
		)
		(fp_line
			(start -0.12065 0.3048)
			(end -0.67945 0.3048)
			(stroke
				(width 0.1)
				(type default)
			)
			(layer "F.Fab")
		)
		(fp_line
			(start 0.120396 0.3048)
			(end 0.120396 0.2794)
			(stroke
				(width 0.1)
				(type default)
			)
			(layer "F.Fab")
		)
		(fp_line
			(start 0.67945 0.3048)
			(end 0.120396 0.3048)
			(stroke
				(width 0.1)
				(type default)
			)
			(layer "F.Fab")
		)
		(fp_line
			(start -0.12065 0.2794)
			(end -0.12065 0.3048)
			(stroke
				(width 0.1)
				(type default)
			)
			(layer "F.Fab")
		)
		(fp_line
			(start 0.120396 0.2794)
			(end -0.12065 0.2794)
			(stroke
				(width 0.1)
				(type default)
			)
			(layer "F.Fab")
		)
		(fp_line
			(start -0.12065 -0.2794)
			(end 0.12065 -0.2794)
			(stroke
				(width 0.1)
				(type default)
			)
			(layer "F.Fab")
		)
		(fp_line
			(start 0.12065 -0.2794)
			(end 0.12065 -0.3048)
			(stroke
				(width 0.1)
				(type default)
			)
			(layer "F.Fab")
		)
		(fp_line
			(start 0.12065 -0.3048)
			(end 0.67945 -0.3048)
			(stroke
				(width 0.1)
				(type default)
			)
			(layer "F.Fab")
		)
		(fp_line
			(start 0.67945 -0.3048)
			(end 0.67945 0.3048)
			(stroke
				(width 0.1)
				(type default)
			)
			(layer "F.Fab")
		)
		(fp_line
			(start -0.67945 -0.305054)
			(end -0.12065 -0.305054)
			(stroke
				(width 0.1)
				(type default)
			)
			(layer "F.Fab")
		)
		(fp_line
			(start -0.12065 -0.305054)
			(end -0.12065 -0.2794)
			(stroke
				(width 0.1)
				(type default)
			)
			(layer "F.Fab")
		)
		(pad "1" smd circle
			(at -0.40005 0 270)
			(size 0 0)
			(layers "F.Cu" "F.Mask" "F.Paste")
			(net "P3V3_AUX_SS")
		)
		(pad "2" smd circle
			(at 0.40005 0 270)
			(size 0 0)
			(layers "F.Cu" "F.Mask" "F.Paste")
			(net "GND")
		)
	)
)
